(kicad_pcb
	(version 20260206)
	(generator "pcbnew")
	(generator_version "10.0")
	(general
		(thickness 1.6)
		(legacy_teardrops no)
	)
	(paper "A4")
	(title_block
		(title "Bryce Canyon_SCC_16316-1_OCP.brd")
		(comment 1 "Bryce Canyon / footprints 1213-1220 of 1561")
	)
	(layers
		(0 "F.Cu" signal "TOP")
		(4 "In1.Cu" signal "L2GND")
		(6 "In2.Cu" signal "L3")
		(8 "In3.Cu" signal "L4VCC")
		(10 "In4.Cu" signal "L5VCC")
		(12 "In5.Cu" signal "L6")
		(14 "In6.Cu" signal "L7GND")
		(2 "B.Cu" signal "BOTTOM")
		(9 "F.Adhes" user "F.Adhesive")
		(11 "B.Adhes" user "B.Adhesive")
		(13 "F.Paste" user "Package Geometry/Pastemask Top")
		(15 "B.Paste" user "Package Geometry/Pastemask Bottom")
		(5 "F.SilkS" user "Ref Des/Silkscreen Top")
		(7 "B.SilkS" user "Ref Des/Silkscreen Bottom")
		(1 "F.Mask" user "Board Geometry/Soldermask Top")
		(3 "B.Mask" user "Board Geometry/Soldermask Bottom")
		(17 "Dwgs.User" user "User.Drawings")
		(19 "Cmts.User" user "User.Comments")
		(21 "Eco1.User" user "User.Eco1")
		(23 "Eco2.User" user "User.Eco2")
		(25 "Edge.Cuts" user "Board Geometry/Outline")
		(27 "Margin" user)
		(31 "F.CrtYd" user "Package Geometry/Place Bound Top")
		(29 "B.CrtYd" user "Package Geometry/Place Bound Bottom")
		(35 "F.Fab" user "Ref Des/Assembly Top")
		(33 "B.Fab" user "Ref Des/Assembly Bottom")
	)
	(footprint ""
		(layer "B.Cu")
		(at 101.7778 -44.2214 180)
		(property "Reference" "C81"
			(at 0 0 0)
			(layer "B.SilkS")
			(hide yes)
			(effects
				(font
					(size 1.27 1.27)
				)
				(justify mirror)
			)
		)
		(property "Value" "SCD01U16V1KX-GP"
			(at 2.8321 -1.7399 180)
			(unlocked yes)
			(layer "B.Fab")
			(hide yes)
			(effects
				(font
					(size 1.016 1.016)
					(thickness 0.1524)
				)
				(justify mirror)
			)
		)
		(property "Device Type" "C0201H13"
			(at 2.8321 -3.2639 180)
			(unlocked yes)
			(layer "B.Fab")
			(hide yes)
			(effects
				(font
					(size 1.016 1.016)
					(thickness 0.1524)
				)
				(justify mirror)
			)
		)
		(duplicate_pad_numbers_are_jumpers no)
		(fp_rect
			(start 0.2794 0.6477)
			(end -0.2794 -0.6477)
			(stroke
				(width 0)
				(type default)
			)
			(fill no)
			(layer "B.CrtYd")
		)
		(fp_rect
			(start 0.2794 0.6477)
			(end -0.2794 -0.6477)
			(stroke
				(width 0)
				(type default)
			)
			(fill no)
			(layer "B.Fab")
		)
		(pad "1" smd custom
			(at 0 -0.2794)
			(size 0.0762 0.0762)
			(layers "B.Cu" "B.Mask" "B.Paste")
			(net "PHY_DPB_TO_SCC_19_DP")
			(options
				(clearance outline)
				(anchor circle)
			)
			(primitives
				(gr_poly
					(pts
						(arc
							(start 0.1524 0.127)
							(mid 0.137521 0.162921)
							(end 0.1016 0.1778)
						)
						(arc
							(start -0.1016 0.1778)
							(mid -0.137521 0.162921)
							(end -0.1524 0.127)
						)
						(arc
							(start -0.1524 -0.127)
							(mid -0.137521 -0.162921)
							(end -0.1016 -0.1778)
						)
						(arc
							(start 0.1016 -0.1778)
							(mid 0.137521 -0.162921)
							(end 0.1524 -0.127)
						)
					)
					(width 0)
					(fill yes)
				)
			)
		)
		(pad "2" smd custom
			(at 0 0.2794)
			(size 0.0762 0.0762)
			(layers "B.Cu" "B.Mask" "B.Paste")
			(net "PHY_DPB_TO_SCC_C_19_DP")
			(options
				(clearance outline)
				(anchor circle)
			)
			(primitives
				(gr_poly
					(pts
						(arc
							(start 0.1524 0.127)
							(mid 0.137521 0.162921)
							(end 0.1016 0.1778)
						)
						(arc
							(start -0.1016 0.1778)
							(mid -0.137521 0.162921)
							(end -0.1524 0.127)
						)
						(arc
							(start -0.1524 -0.127)
							(mid -0.137521 -0.162921)
							(end -0.1016 -0.1778)
						)
						(arc
							(start 0.1016 -0.1778)
							(mid 0.137521 -0.162921)
							(end 0.1524 -0.127)
						)
					)
					(width 0)
					(fill yes)
				)
			)
		)
	)
	(footprint ""
		(layer "B.Cu")
		(at 92.123006 -74.762614 180)
		(property "Reference" "C204"
			(at 0 0 0)
			(layer "B.SilkS")
			(hide yes)
			(effects
				(font
					(size 1.27 1.27)
				)
				(justify mirror)
			)
		)
		(property "Value" "SC22U6D3V3MX-9-GP-U"
			(at 0 -2.8194 180)
			(unlocked yes)
			(layer "B.Fab")
			(hide yes)
			(effects
				(font
					(size 1.016 1.016)
					(thickness 0.1524)
				)
				(justify mirror)
			)
		)
		(property "Device Type" "C603H40"
			(at 0 -4.3434 180)
			(unlocked yes)
			(layer "B.Fab")
			(hide yes)
			(effects
				(font
					(size 1.016 1.016)
					(thickness 0.1524)
				)
				(justify mirror)
			)
		)
		(duplicate_pad_numbers_are_jumpers no)
		(fp_line
			(start -0.508 0)
			(end 0.508 0)
			(stroke
				(width 0.2032)
				(type default)
			)
			(layer "B.SilkS")
		)
		(fp_rect
			(start 0.5842 1.3335)
			(end -0.5842 -1.3335)
			(stroke
				(width 0)
				(type default)
			)
			(fill no)
			(layer "B.CrtYd")
		)
		(fp_rect
			(start 0.5842 1.3335)
			(end -0.5842 -1.3335)
			(stroke
				(width 0)
				(type default)
			)
			(fill no)
			(layer "B.Fab")
		)
		(pad "1" smd custom
			(at 0 -0.762)
			(size 0.2159 0.2159)
			(layers "B.Cu" "B.Mask" "B.Paste")
			(net "XTAL_VDDA09")
			(options
				(clearance outline)
				(anchor circle)
			)
			(primitives
				(gr_poly
					(pts
						(arc
							(start -0.3302 0.4318)
							(mid -0.402042 0.402042)
							(end -0.4318 0.3302)
						)
						(arc
							(start -0.4318 -0.3302)
							(mid -0.402042 -0.402042)
							(end -0.3302 -0.4318)
						)
						(arc
							(start 0.3302 -0.4318)
							(mid 0.402042 -0.402042)
							(end 0.4318 -0.3302)
						)
						(arc
							(start 0.4318 0.3302)
							(mid 0.402042 0.402042)
							(end 0.3302 0.4318)
						)
					)
					(width 0)
					(fill yes)
				)
			)
		)
		(pad "2" smd custom
			(at 0 0.762)
			(size 0.2159 0.2159)
			(layers "B.Cu" "B.Mask" "B.Paste")
			(net "GND")
			(options
				(clearance outline)
				(anchor circle)
			)
			(primitives
				(gr_poly
					(pts
						(arc
							(start -0.3302 0.4318)
							(mid -0.402042 0.402042)
							(end -0.4318 0.3302)
						)
						(arc
							(start -0.4318 -0.3302)
							(mid -0.402042 -0.402042)
							(end -0.3302 -0.4318)
						)
						(arc
							(start 0.3302 -0.4318)
							(mid 0.402042 -0.402042)
							(end 0.4318 -0.3302)
						)
						(arc
							(start 0.4318 0.3302)
							(mid 0.402042 0.402042)
							(end 0.3302 0.4318)
						)
					)
					(width 0)
					(fill yes)
				)
			)
		)
	)
	(footprint ""
		(layer "B.Cu")
		(at 134.846822 -56.379618 180)
		(property "Reference" "C26"
			(at 0 0 0)
			(layer "B.SilkS")
			(hide yes)
			(effects
				(font
					(size 1.27 1.27)
				)
				(justify mirror)
			)
		)
		(property "Value" "SCD01U16V1KX-GP"
			(at 2.8321 -1.7399 180)
			(unlocked yes)
			(layer "B.Fab")
			(hide yes)
			(effects
				(font
					(size 1.016 1.016)
					(thickness 0.1524)
				)
				(justify mirror)
			)
		)
		(property "Device Type" "C0201H13"
			(at 2.8321 -3.2639 180)
			(unlocked yes)
			(layer "B.Fab")
			(hide yes)
			(effects
				(font
					(size 1.016 1.016)
					(thickness 0.1524)
				)
				(justify mirror)
			)
		)
		(duplicate_pad_numbers_are_jumpers no)
		(fp_rect
			(start 0.2794 0.6477)
			(end -0.2794 -0.6477)
			(stroke
				(width 0)
				(type default)
			)
			(fill no)
			(layer "B.CrtYd")
		)
		(fp_rect
			(start 0.2794 0.6477)
			(end -0.2794 -0.6477)
			(stroke
				(width 0)
				(type default)
			)
			(fill no)
			(layer "B.Fab")
		)
		(pad "1" smd custom
			(at 0 -0.2794)
			(size 0.0762 0.0762)
			(layers "B.Cu" "B.Mask" "B.Paste")
			(net "PHY_DPB_TO_SCC_31_DN")
			(options
				(clearance outline)
				(anchor circle)
			)
			(primitives
				(gr_poly
					(pts
						(arc
							(start 0.1524 0.127)
							(mid 0.137521 0.162921)
							(end 0.1016 0.1778)
						)
						(arc
							(start -0.1016 0.1778)
							(mid -0.137521 0.162921)
							(end -0.1524 0.127)
						)
						(arc
							(start -0.1524 -0.127)
							(mid -0.137521 -0.162921)
							(end -0.1016 -0.1778)
						)
						(arc
							(start 0.1016 -0.1778)
							(mid 0.137521 -0.162921)
							(end 0.1524 -0.127)
						)
					)
					(width 0)
					(fill yes)
				)
			)
		)
		(pad "2" smd custom
			(at 0 0.2794)
			(size 0.0762 0.0762)
			(layers "B.Cu" "B.Mask" "B.Paste")
			(net "PHY_DPB_TO_SCC_C_31_DN")
			(options
				(clearance outline)
				(anchor circle)
			)
			(primitives
				(gr_poly
					(pts
						(arc
							(start 0.1524 0.127)
							(mid 0.137521 0.162921)
							(end 0.1016 0.1778)
						)
						(arc
							(start -0.1016 0.1778)
							(mid -0.137521 0.162921)
							(end -0.1524 0.127)
						)
						(arc
							(start -0.1524 -0.127)
							(mid -0.137521 -0.162921)
							(end -0.1016 -0.1778)
						)
						(arc
							(start 0.1016 -0.1778)
							(mid 0.137521 -0.162921)
							(end 0.1524 -0.127)
						)
					)
					(width 0)
					(fill yes)
				)
			)
		)
	)
	(footprint ""
		(layer "B.Cu")
		(at 181.6354 -27.2542 90)
		(property "Reference" "TP56"
			(at 0 0 90)
			(layer "B.SilkS")
			(hide yes)
			(effects
				(font
					(size 1.27 1.27)
				)
				(justify mirror)
			)
		)
		(property "Value" "TPAD28-2-GP"
			(at 0.0127 -1.6637 90)
			(unlocked yes)
			(layer "B.Fab")
			(hide yes)
			(effects
				(font
					(size 1.016 1.016)
					(thickness 0.1524)
				)
				(justify mirror)
			)
		)
		(property "Device Type" "TPAD28"
			(at 0.0127 -3.1877 90)
			(unlocked yes)
			(layer "B.Fab")
			(hide yes)
			(effects
				(font
					(size 1.016 1.016)
					(thickness 0.1524)
				)
				(justify mirror)
			)
		)
		(duplicate_pad_numbers_are_jumpers no)
		(fp_poly
			(pts
				(arc
					(start 0 0.3556)
					(mid 0 -0.3556)
					(end 0 0.3556)
				)
			)
			(stroke
				(width 0)
				(type default)
			)
			(fill no)
			(layer "B.CrtYd")
		)
		(fp_poly
			(pts
				(arc
					(start 0 0.6096)
					(mid 0 -0.6096)
					(end 0 0.6096)
				)
			)
			(stroke
				(width 0)
				(type default)
			)
			(fill no)
			(layer "B.Fab")
		)
		(pad "1" smd circle
			(at 0 0 270)
			(size 0.7112 0.7112)
			(layers "B.Cu" "B.Mask" "B.Paste")
			(net "IOC_GPIO_3")
		)
	)
	(footprint ""
		(layer "B.Cu")
		(at 113.411 -71.9074)
		(property "Reference" "C142"
			(at 0 0 0)
			(layer "B.SilkS")
			(hide yes)
			(effects
				(font
					(size 1.27 1.27)
				)
				(justify mirror)
			)
		)
		(property "Value" "SCD1U6D3V1KX-GP"
			(at 2.8321 -1.7399 0)
			(unlocked yes)
			(layer "B.Fab")
			(hide yes)
			(effects
				(font
					(size 1.016 1.016)
					(thickness 0.1524)
				)
				(justify mirror)
			)
		)
		(property "Device Type" "C0201H13"
			(at 2.8321 -3.2639 0)
			(unlocked yes)
			(layer "B.Fab")
			(hide yes)
			(effects
				(font
					(size 1.016 1.016)
					(thickness 0.1524)
				)
				(justify mirror)
			)
		)
		(duplicate_pad_numbers_are_jumpers no)
		(fp_rect
			(start 0.2794 0.6477)
			(end -0.2794 -0.6477)
			(stroke
				(width 0)
				(type default)
			)
			(fill no)
			(layer "B.CrtYd")
		)
		(fp_rect
			(start 0.2794 0.6477)
			(end -0.2794 -0.6477)
			(stroke
				(width 0)
				(type default)
			)
			(fill no)
			(layer "B.Fab")
		)
		(pad "1" smd custom
			(at 0 -0.2794 180)
			(size 0.0762 0.0762)
			(layers "B.Cu" "B.Mask" "B.Paste")
			(net "P1V8_E")
			(options
				(clearance outline)
				(anchor circle)
			)
			(primitives
				(gr_poly
					(pts
						(arc
							(start 0.1524 0.127)
							(mid 0.137521 0.162921)
							(end 0.1016 0.1778)
						)
						(arc
							(start -0.1016 0.1778)
							(mid -0.137521 0.162921)
							(end -0.1524 0.127)
						)
						(arc
							(start -0.1524 -0.127)
							(mid -0.137521 -0.162921)
							(end -0.1016 -0.1778)
						)
						(arc
							(start 0.1016 -0.1778)
							(mid 0.137521 -0.162921)
							(end 0.1524 -0.127)
						)
					)
					(width 0)
					(fill yes)
				)
			)
		)
		(pad "2" smd custom
			(at 0 0.2794 180)
			(size 0.0762 0.0762)
			(layers "B.Cu" "B.Mask" "B.Paste")
			(net "GND")
			(options
				(clearance outline)
				(anchor circle)
			)
			(primitives
				(gr_poly
					(pts
						(arc
							(start 0.1524 0.127)
							(mid 0.137521 0.162921)
							(end 0.1016 0.1778)
						)
						(arc
							(start -0.1016 0.1778)
							(mid -0.137521 0.162921)
							(end -0.1524 0.127)
						)
						(arc
							(start -0.1524 -0.127)
							(mid -0.137521 -0.162921)
							(end -0.1016 -0.1778)
						)
						(arc
							(start 0.1016 -0.1778)
							(mid 0.137521 -0.162921)
							(end 0.1524 -0.127)
						)
					)
					(width 0)
					(fill yes)
				)
			)
		)
	)
	(footprint ""
		(layer "B.Cu")
		(at 165.197282 -28.269184 -90)
		(property "Reference" "C392"
			(at 0 0 90)
			(layer "B.SilkS")
			(hide yes)
			(effects
				(font
					(size 1.27 1.27)
				)
				(justify mirror)
			)
		)
		(property "Value" "SCD1U6D3V1KX-GP"
			(at 2.8321 -1.7399 270)
			(unlocked yes)
			(layer "B.Fab")
			(hide yes)
			(effects
				(font
					(size 1.016 1.016)
					(thickness 0.1524)
				)
				(justify mirror)
			)
		)
		(property "Device Type" "C0201H13"
			(at 2.8321 -3.2639 270)
			(unlocked yes)
			(layer "B.Fab")
			(hide yes)
			(effects
				(font
					(size 1.016 1.016)
					(thickness 0.1524)
				)
				(justify mirror)
			)
		)
		(duplicate_pad_numbers_are_jumpers no)
		(fp_rect
			(start 0.2794 0.6477)
			(end -0.2794 -0.6477)
			(stroke
				(width 0)
				(type default)
			)
			(fill no)
			(layer "B.CrtYd")
		)
		(fp_rect
			(start 0.2794 0.6477)
			(end -0.2794 -0.6477)
			(stroke
				(width 0)
				(type default)
			)
			(fill no)
			(layer "B.Fab")
		)
		(pad "1" smd custom
			(at 0 -0.2794 90)
			(size 0.0762 0.0762)
			(layers "B.Cu" "B.Mask" "B.Paste")
			(net "PCE_AVDD")
			(options
				(clearance outline)
				(anchor circle)
			)
			(primitives
				(gr_poly
					(pts
						(arc
							(start 0.1524 0.127)
							(mid 0.137521 0.162921)
							(end 0.1016 0.1778)
						)
						(arc
							(start -0.1016 0.1778)
							(mid -0.137521 0.162921)
							(end -0.1524 0.127)
						)
						(arc
							(start -0.1524 -0.127)
							(mid -0.137521 -0.162921)
							(end -0.1016 -0.1778)
						)
						(arc
							(start 0.1016 -0.1778)
							(mid 0.137521 -0.162921)
							(end 0.1524 -0.127)
						)
					)
					(width 0)
					(fill yes)
				)
			)
		)
		(pad "2" smd custom
			(at 0 0.2794 90)
			(size 0.0762 0.0762)
			(layers "B.Cu" "B.Mask" "B.Paste")
			(net "GND")
			(options
				(clearance outline)
				(anchor circle)
			)
			(primitives
				(gr_poly
					(pts
						(arc
							(start 0.1524 0.127)
							(mid 0.137521 0.162921)
							(end 0.1016 0.1778)
						)
						(arc
							(start -0.1016 0.1778)
							(mid -0.137521 0.162921)
							(end -0.1524 0.127)
						)
						(arc
							(start -0.1524 -0.127)
							(mid -0.137521 -0.162921)
							(end -0.1016 -0.1778)
						)
						(arc
							(start 0.1016 -0.1778)
							(mid 0.137521 -0.162921)
							(end 0.1524 -0.127)
						)
					)
					(width 0)
					(fill yes)
				)
			)
		)
	)
	(footprint ""
		(layer "B.Cu")
		(at 183.3626 -41.7068 -90)
		(property "Reference" "C477"
			(at 0 0 90)
			(layer "B.SilkS")
			(hide yes)
			(effects
				(font
					(size 1.27 1.27)
				)
				(justify mirror)
			)
		)
		(property "Value" "SCD1U6D3V1KX-GP"
			(at 2.8321 -1.7399 270)
			(unlocked yes)
			(layer "B.Fab")
			(hide yes)
			(effects
				(font
					(size 1.016 1.016)
					(thickness 0.1524)
				)
				(justify mirror)
			)
		)
		(property "Device Type" "C0201H13"
			(at 2.8321 -3.2639 270)
			(unlocked yes)
			(layer "B.Fab")
			(hide yes)
			(effects
				(font
					(size 1.016 1.016)
					(thickness 0.1524)
				)
				(justify mirror)
			)
		)
		(duplicate_pad_numbers_are_jumpers no)
		(fp_rect
			(start 0.2794 0.6477)
			(end -0.2794 -0.6477)
			(stroke
				(width 0)
				(type default)
			)
			(fill no)
			(layer "B.CrtYd")
		)
		(fp_rect
			(start 0.2794 0.6477)
			(end -0.2794 -0.6477)
			(stroke
				(width 0)
				(type default)
			)
			(fill no)
			(layer "B.Fab")
		)
		(pad "1" smd custom
			(at 0 -0.2794 90)
			(size 0.0762 0.0762)
			(layers "B.Cu" "B.Mask" "B.Paste")
			(net "P1V8_C")
			(options
				(clearance outline)
				(anchor circle)
			)
			(primitives
				(gr_poly
					(pts
						(arc
							(start 0.1524 0.127)
							(mid 0.137521 0.162921)
							(end 0.1016 0.1778)
						)
						(arc
							(start -0.1016 0.1778)
							(mid -0.137521 0.162921)
							(end -0.1524 0.127)
						)
						(arc
							(start -0.1524 -0.127)
							(mid -0.137521 -0.162921)
							(end -0.1016 -0.1778)
						)
						(arc
							(start 0.1016 -0.1778)
							(mid 0.137521 -0.162921)
							(end 0.1524 -0.127)
						)
					)
					(width 0)
					(fill yes)
				)
			)
		)
		(pad "2" smd custom
			(at 0 0.2794 90)
			(size 0.0762 0.0762)
			(layers "B.Cu" "B.Mask" "B.Paste")
			(net "GND")
			(options
				(clearance outline)
				(anchor circle)
			)
			(primitives
				(gr_poly
					(pts
						(arc
							(start 0.1524 0.127)
							(mid 0.137521 0.162921)
							(end 0.1016 0.1778)
						)
						(arc
							(start -0.1016 0.1778)
							(mid -0.137521 0.162921)
							(end -0.1524 0.127)
						)
						(arc
							(start -0.1524 -0.127)
							(mid -0.137521 -0.162921)
							(end -0.1016 -0.1778)
						)
						(arc
							(start 0.1016 -0.1778)
							(mid 0.137521 -0.162921)
							(end 0.1524 -0.127)
						)
					)
					(width 0)
					(fill yes)
				)
			)
		)
	)
	(footprint ""
		(layer "B.Cu")
		(at 79.8322 -73.6854 -90)
		(property "Reference" "C117"
			(at 0 0 90)
			(layer "B.SilkS")
			(hide yes)
			(effects
				(font
					(size 1.27 1.27)
				)
				(justify mirror)
			)
		)
		(property "Value" "SCD1U16V2KX-3GP"
			(at -1.1811 -2.7051 270)
			(unlocked yes)
			(layer "B.Fab")
			(hide yes)
			(effects
				(font
					(size 1.016 1.016)
					(thickness 0.1524)
				)
				(justify mirror)
			)
		)
		(property "Device Type" "C402H22"
			(at -1.1811 -4.2291 270)
			(unlocked yes)
			(layer "B.Fab")
			(hide yes)
			(effects
				(font
					(size 1.016 1.016)
					(thickness 0.1524)
				)
				(justify mirror)
			)
		)
		(duplicate_pad_numbers_are_jumpers no)
		(fp_rect
			(start 0.4318 0.9525)
			(end -0.4318 -0.9525)
			(stroke
				(width 0)
				(type default)
			)
			(fill no)
			(layer "B.CrtYd")
		)
		(fp_rect
			(start 0.4318 0.9525)
			(end -0.4318 -0.9525)
			(stroke
				(width 0)
				(type default)
			)
			(fill no)
			(layer "B.Fab")
		)
		(pad "1" smd custom
			(at 0 -0.4445 90)
			(size 0.1524 0.1524)
			(layers "B.Cu" "B.Mask" "B.Paste")
			(net "P3V3")
			(options
				(clearance outline)
				(anchor circle)
			)
			(primitives
				(gr_poly
					(pts
						(arc
							(start 0.3048 0.2032)
							(mid 0.275042 0.275042)
							(end 0.2032 0.3048)
						)
						(arc
							(start -0.2032 0.3048)
							(mid -0.275042 0.275042)
							(end -0.3048 0.2032)
						)
						(arc
							(start -0.3048 -0.2032)
							(mid -0.275042 -0.275042)
							(end -0.2032 -0.3048)
						)
						(arc
							(start 0.2032 -0.3048)
							(mid 0.275042 -0.275042)
							(end 0.3048 -0.2032)
						)
					)
					(width 0)
					(fill yes)
				)
			)
		)
		(pad "2" smd custom
			(at 0 0.4445 90)
			(size 0.1524 0.1524)
			(layers "B.Cu" "B.Mask" "B.Paste")
			(net "GND")
			(options
				(clearance outline)
				(anchor circle)
			)
			(primitives
				(gr_poly
					(pts
						(arc
							(start 0.3048 0.2032)
							(mid 0.275042 0.275042)
							(end 0.2032 0.3048)
						)
						(arc
							(start -0.2032 0.3048)
							(mid -0.275042 0.275042)
							(end -0.3048 0.2032)
						)
						(arc
							(start -0.3048 -0.2032)
							(mid -0.275042 -0.275042)
							(end -0.2032 -0.3048)
						)
						(arc
							(start 0.2032 -0.3048)
							(mid 0.275042 -0.275042)
							(end 0.3048 -0.2032)
						)
					)
					(width 0)
					(fill yes)
				)
			)
		)
	)
)
